FILE_TYPE = CONNECTIVITY;
{Allegro Design Entry HDL 16.6-p007 (v16-6-112F) 10/10/2012}
"PAGE_NUMBER" = 119;
0"NC";
1"P3V3_STBY\g";
2"GND\g";
3"P3V3_STBY\g";
4"GND\g";
5"P3V3_STBY\g";
6"P3V3_STBY\g";
7"P3V3_STBY\g";
8"IRQ_BMC_PCH_NMI_STBY_R_N";
9"FM_PWR_LED_N";
10"IRQ_HSC_FAULT_N";
11"IRQ_MEZZ_LAN_ALERT_N";
12"FM_PCH_PLD_DATA_R";
13"FM_BMC_ENABLE_N";
14"FM_CPLD_BMC_PWRDN_N";
15"SGPIO_PCH_SSATA_DOUT0";
16"H_CPU0_FAST_WAKE_LVT3_N";
17"FM_BMC_FAULT_LED_N";
18"FM_BMC_CPLD_GPO";
19"FM_BMC_HEARTBEAT_N";
20"FM_ADR_MODE_SEL_R";
21"FM_XRC_READY_N";
22"FM_XRC_PRESENT_N";
23"IRQ_OOB_MGMT_RISER_ALERT_N";
24"SMB_SLOTX24_PCH_STBY_LVC3_SDA";
25"FM_TPM_PRES_RST_N";
26"FM_BMC_ENABLE_N";
27"SMB_SLOTX24_PCH_STBY_LVC3_SCL";
28"IRQ_LOM_ALERT_N";
29"FM_PCH_PLD_DATA";
30"FM_PWR_LED_A";
31"FM_PWR_LED_N";
32"FM_PWR_LED";
33"FM_PWR_LED_K";
34"RST_PCH_SYSRST_BTN_OUT_N";
35"FM_PWRBRK_SLOT_N";
36"FM_THROTTLE_N";
37"FM_PASSWORD_CLEAR_N";
38"SMB_PMBUS_BMC_STBY_LVC3_SDA_R1";
39"SMB_PMBUS_BMC_STBY_LVC3_SCL_R1";
40"IRQ_SML0_ALERT_N";
41"FM_PMBUS_ALERT_BUF_EN_N";
42"FM_BOARD_REV_ID2";
43"FM_PCH_SATA_RAID_KEY";
44"FM_CPU1_RC_EN";
45"SMB_SMLINK0_STBY_LVC3_SDA_R1";
46"SMB_SMLINK0_STBY_LVC3_SCL_R1";
47"PU_PCH_TLS_ENABLE_STRAP";
48"SMB_HOST_STBY_LVC3_SDA_R1";
49"SMB_HOST_STBY_LVC3_SCL_R1";
50"FM_CPU0_THERMTRIP_LATCH_LVT3_N";
51"FM_SLT_CFG1";
52"IRQ_BMC_PCH_SCI_LPC_N";
53"FM_BOARD_REV_ID0";
54"FM_BOARD_REV_ID1";
55"FM_SLT_CFG0";
56"FM_SLT_CFG2_R";
57"FM_PMBUS_ALERT_BUF_EN_R_N";
58"FM_BB_BMC_MP_GPIO";
59"FM_CPU_CATERR_DLY_LVT3_N";
60"IRQ_BMC_PCH_SMI_LPC_N";
61"FM_BIOS_POST_CMPLT_N";
62"FM_CPU_CATERR_DLY_LVT3_R_N";
63"FM_THROTTLE_R2_N";
64"IRQ_PIRQA_SPI_TPM_N";
65"IRQ_LPC_SERIRQ_N";
66"LPC_LAD3_IO3";
67"LPC_LAD2_IO2";
68"LPC_LAD0_IO0";
69"PU_FM_RCIN_N";
70"LPC_LAD1_IO1";
71"FM_FAST_PROCHOT_EN_N";
72"FM_BIOS_PREFRB2_GOOD";
73"FM_BIOS_POST_CMPLT_N";
74"FM_USB_P0_EN_BOOT_BIOS_STRAP_N";
75"FM_PCH_BMC_THERMTRIP_EXI_STRAP_N";
76"LPC_LAD_IO<3:0>";
77"IRQ_PVDDQ_DEF_VRHOT_LVT3_N";
78"FM_QAT_EN_N";
79"PU_IRQ_VRALERT_N";
80"IRQ_FORCE_NM_THROTTLE_N";
81"LPC_LFRAME_N_CS0_N";
82"CLK_24M_BMC_LPC";
83"FM_PWR_BTN_N";
84"FP_NMI_BTN_N";
85"IRQ_PVDDQ_KLM_VRHOT_LVT3_N";
86"IRQ_PVDDQ_GHJ_VRHOT_LVT3_N";
87"IRQ_PVDDQ_ABC_VRHOT_LVT3_N";
88"VID_PCH_CORE_PVNN_AUX_VID_1";
89"FM_UV_ADR_TRIGGER_EN";
90"FM_PCH_PWRBTN_OUT_N";
91"IRQ_PCH_NIC_ALERT_N";
92"FM_UART_ALERT_N";
93"FM_BIOS_TOP_SWAP_SPKR";
94"RST_PLTRST_N";
95"FM_GLOBAL_RST_WARN_N";
96"FM_PMBUS_ALERT_BUF_EN_R2_N";
97"RST_SYSTEM_BTN_N";
98"VID_PCH_CORE_PVNN_AUX_VID_0";
99"FM_PMBUS_ALERT_BUF_EN_N";
100"FM_ADR_MODE_SEL";
101"FM_BMC_READY_N";
102"FM_OCP_MEZZA_PRES";
103"PU_LPC_CLKRUN_N";
104"CLK_24M_BMC_LPC_R";
105"PU_LPC_PME_N";
106"PU_IRQ_PCH_SCI_WHEA_N";
107"FM_MB_SLOT_ID0";
108"FM_MB_SLOT_ID1";
109"FM_MB_SLOT_ID2";
110"FM_OCP_MEZZA_PRES_R";
111"FM_TPM_PRES_N";
112"FM_BMC_READY_R_N";
113"FM_ME_RECOVER_N";
114"FM_CPU_BMC_INIT";
115"FM_UART_PRES_N";
%"LBG_CORE_QAT_EXT_D"
"6","(-4100,3200)","0","mstr_u_proc","I115";
;
CDS_SEC"6"
PART_NUMBER"H91415-002"
LOCATION"U7C1"
MATERIAL"IC"
CDS_LIB"mstr_u_proc"
SEC"6"
CDS_LOCATION"U7C1"
PACK_TYPE"BGA1"
SEC_TYPE"BGA1"
BOM_COST"SB"
ROOM"SB";
"GPP_D9_SSATA_DEVSLP3"
$PN"BY42"80;
"GPP_D8"
$PN"BR38"17;
"GPP_D7"
$PN"CA45"18;
"GPP_D6"
$PN"BW41"14;
"GPP_D5"
$PN"BM38"13;
"GPP_D4"
$PN"BM42"12;
"GPP_D3"
$PN"BW45"11;
"GPP_D23"
$PN"BN44"50;
"GPP_D22_IE_UART_TX"
$PN"BR46"0;
"GPP_D21_IE_UART_RX"
$PN"BV44"0;
"GPP_D20"
$PN"CA48"19;
"GPP_D2"
$PN"BJ44"10;
"GPP_D19"
$PN"CA43"20;
"GPP_D18"
$PN"CA41"21;
"GPP_D17"
$PN"BW48"22;
"GPP_D16_SML0BALERT_IE_N"
$PN"BV42"23;
"GPP_D15_SSATA_SDATAOUT0"
$PN"BW43"15;
"GPP_D14_SML0BDATA_IE"
$PN"BL44"24;
"GPP_D13_SML0BCLK_IE"
$PN"BY44"27;
"GPP_D12_SSATA_SDATAOUT1"
$PN"BN40"25;
"GPP_D11_SSATA_DEVSLP5"
$PN"BY47"28;
"GPP_D10_SSATA_DEVSLP4"
$PN"BV47"16;
"GPP_D1"
$PN"BK46"9;
"GPP_D0"
$PN"BR42"8;
"GPP_C9"
$PN"BY29"44;
"GPP_C8"
$PN"BW32"37;
"GPP_C7_SML1DATA_IE"
$PN"BV35"38;
"GPP_C6_SML1CLK_IE"
$PN"CA28"39;
"GPP_C5_SML0ALERT_IE_N"
$PN"BW34"40;
"GPP_C4_SML0DATA_IE"
$PN"BW30"45;
"GPP_C3_SML0CLK_IE"
$PN"BV29"46;
"GPP_C2_SMBALERT_N"
$PN"BY27"47;
"GPP_C23"
$PN"CA37"62;
"GPP_C22"
$PN"CA34"60;
"GPP_C21"
$PN"BY33"61;
"GPP_C20"
$PN"CA39"63;
"GPP_C1_SMBDATA"
$PN"BV27"48;
"GPP_C19"
$PN"BW39"58;
"GPP_C18"
$PN"BY35"57;
"GPP_C17"
$PN"BY31"56;
"GPP_C16"
$PN"BW37"51;
"GPP_C15"
$PN"CA32"55;
"GPP_C14"
$PN"BY38"52;
"GPP_C13"
$PN"BV38"54;
"GPP_C12"
$PN"CA30"53;
"GPP_C11"
$PN"BV33"42;
"GPP_C10"
$PN"BV31"43;
"GPP_C0_SMBCLK"
$PN"BW28"49;
"GPP_B9_SRCCLKREQ4_N"
$PN"BH20"83;
"GPP_B8_SRCCLKREQ3_N"
$PN"BN11"84;
"GPP_B7_SRCCLKREQ2_N"
$PN"BR13"85;
"GPP_B6_SRCCLKREQ1_N"
$PN"BG18"86;
"GPP_B5_SRCCLKREQ0_N"
$PN"BK17"77;
"GPP_B4_CPU_GP3"
$PN"BN7"87;
"GPP_B3_CPU_GP2"
$PN"BR9"78;
"GPP_B23_MEIE_SML1ALRT_N_PHOT_N"
$PN"BM20"75;
"GPP_B22"
$PN"BR17"74;
"GPP_B21"
$PN"BH17"71;
"GPP_B20"
$PN"BJ22"73;
"GPP_B2"
$PN"BN15"79;
"GPP_B1_CORE_VID1"
$PN"BH9"88;
"GPP_B19"
$PN"BK20"72;
"GPP_B18"
$PN"BL15"89;
"GPP_B17"
$PN"BG15"90;
"GPP_B16"
$PN"BG22"91;
"GPP_B15"
$PN"BK13"92;
"GPP_B14_SPKR"
$PN"BH13"93;
"GPP_B13_PLTRST_N"
$PN"BN18"94;
"GPP_B12_GLB_RST_WARN_N"
$PN"BL18"95;
"GPP_B11"
$PN"BK9"96;
"GPP_B10_SRCCLKREQ5_N"
$PN"BL11"97;
"GPP_B0_CORE_VID0"
$PN"BL7"98;
"GPP_A9_CLKOUT_LPC0_ESPI_CLK"
$PN"R3"104;
"GPP_A8_CLKRUN_N"
$PN"AB1"103;
"GPP_A7_PIRQA_N_ESPI_ALERT0_N"
$PN"AA2"64;
"GPP_A6_SERIRQ_ESPI_CS1_N"
$PN"P2"65;
"GPP_A5_LFRAME_N_ESPI_CS0_N"
$PN"P4"81;
"GPP_A4_LAD3_ESPI_IO3"
$PN"Y1"66;
"GPP_A3_LAD2_ESPI_IO2"
$PN"W2"67;
"GPP_A2_LAD1_ESPI_IO1"
$PN"N1"70;
"GPP_A23"
$PN"V1"112;
"GPP_A22"
$PN"AE4"111;
"GPP_A21"
$PN"AE2"110;
"GPP_A20"
$PN"W4"0;
"GPP_A1_LAD0_ESPI_IO0"
$PN"Y3"68;
"GPP_A19"
$PN"V3"113;
"GPP_A18"
$PN"AD3"34;
"GPP_A17"
$PN"AD1"114;
"GPP_A16_CLKOUT_LPC2"
$PN"T2"115;
"GPP_A15_SUSACK_N"
$PN"AC4"109;
"GPP_A14_ESPI_RESET_N"
$PN"AB3"108;
"GPP_A13_SUSWARN_N_SUSPWRDNACK"
$PN"T4"107;
"GPP_A12_BMBUSY_N_SXEXITHLDOFF_N"
$PN"R1"106;
"GPP_A11_PME_N"
$PN"AC2"105;
"GPP_A10_CLKOUT_LPC1"
$PN"AA4"0;
"GPP_A0_RCIN_N_ESPI_ALERT1_N"
$PN"N3"69;
%"TAP"
"6","(-6975,3300)","0","mstr_standard","I120";
;
HDL_TAP"TRUE"
BODY_TYPE"PLUMBING"
CDS_LIB"mstr_standard";
"B \NAC \NWC"76;
"S \NAC"
BN"0"68;
%"TAP"
"6","(-6975,3350)","0","mstr_standard","I121";
;
HDL_TAP"TRUE"
BODY_TYPE"PLUMBING"
CDS_LIB"mstr_standard";
"B \NAC \NWC"76;
"S \NAC"
BN"1"70;
%"TAP"
"6","(-6975,3400)","0","mstr_standard","I122";
;
HDL_TAP"TRUE"
BODY_TYPE"PLUMBING"
CDS_LIB"mstr_standard";
"B \NAC \NWC"76;
"S \NAC"
BN"2"67;
%"TAP"
"6","(-6975,3450)","0","mstr_standard","I123";
;
HDL_TAP"TRUE"
BODY_TYPE"PLUMBING"
CDS_LIB"mstr_standard";
"B \NAC \NWC"76;
"S \NAC"
BN"3"66;
%"RES"
"1","(-1450,2200)","0","mstr_discrete","I172";
;
CDS_SEC"1"
LOCATION"R2M3"
PACK_TYPE"0402"
WATTAGE"1/16W"
VALUE"33.2"
TOLERANCE"1%"
MATERIAL"CHIP"
PART_NUMBER"G21796-074"
ROOM"CPLD"
SEC_TYPE"0402"
SEC"1"
CDS_LIB"mstr_discrete"
CDS_LOCATION"R2M3";
"B"
$PN"2"29;
"A"
$PN"1"12;
%"RES"
"1","(-1550,4400)","0","mstr_discrete","I173";
;
CDS_SEC"1"
VALUE"33.2"
MATERIAL"CHIP"
PART_NUMBER"G21796-074"
TOLERANCE"1%"
WATTAGE"1/16W"
LOCATION"R2N1"
PACK_TYPE"0402"
SEC"1"
SEC_TYPE"0402"
ROOM"CPLD"
CDS_LOCATION"R2N1"
CDS_LIB"mstr_discrete";
"B"
$PN"2"59;
"A"
$PN"1"62;
%"RES"
"1","(-1475,2950)","0","mstr_discrete","I174";
;
CDS_SEC"1"
PACK_TYPE"0402"
MATERIAL"CHIP"
TOLERANCE"1%"
VALUE"33.2"
LOCATION"R2M7"
WATTAGE"1/16W"
PART_NUMBER"G21796-074"
ROOM"CPLD"
SEC"1"
SEC_TYPE"0402"
CDS_LIB"mstr_discrete"
CDS_LOCATION"R2M7";
"B"
$PN"2"100;
"A"
$PN"1"20;
%"FET_N_DUAL"
"5","(-4725,725)","0","mstr_discrete","I175";
;
CDS_SEC"1"
PART_NUMBER"E40049-001"
MATERIAL"FET"
VALUE"NTJD4001N"
LOCATION"Q9A2"
CDS_LOCATION"Q9A2"
ROOM"SB"
SEC_TYPE"SMLF"
BOM_COST"SB"
SEC"1"
CDS_LIB"mstr_discrete"
PACK_TYPE"SMLF";
"GATE <SIZE -1..0>"
$PN"2"31;
"SOURCE <SIZE-1..0>"
$PN"1"4;
"DRAIN <SIZE -1..0>"
$PN"6"32;
%"P3V3_STBY"
"1","(-2700,1700)","0","mstr_symbols","I177";
;
VOLTAGE"3.3V"
CDS_LIB"mstr_symbols"
SIZE"1B"
BODY_TYPE"PLUMBING"
HDL_POWER"P3V3_STBY";
"G\NAC"1;
%"RES"
"1","(-2900,1525)","0","mstr_discrete","I178";
;
CDS_SEC"1"
PACK_TYPE"0402"
WATTAGE"1/16W"
VALUE"221"
MATERIAL"CHIP"
TOLERANCE"1.0%"
PART_NUMBER"G21796-271"
LOCATION"R9A20"
SEC"1"
BOM_COST"SB"
SEC_TYPE"0402"
CDS_LIB"mstr_discrete"
CDS_LOCATION"R9A20"
ROOM"SB";
"B"
$PN"2"1;
"A"
$PN"1"30;
%"LED"
"3","(-3550,1525)","0","mstr_discrete","I179";
;
CDS_SEC"1"
PART_NUMBER"C97278-010"
LOCATION"DS9A5"
MATERIAL"IC"
COLOR"GREEN"
SEC"1"
ROOM"SB"
PACK_TYPE"A1LF"
SEC_TYPE"A1LF"
BOM_COST"SB"
CDS_LOCATION"DS9A5"
CDS_LIB"mstr_discrete";
"A"
$PN"1"30;
"C"
$PN"2"33;
%"FET_N_DUAL"
"5","(-3950,1200)","0","mstr_discrete","I180";
;
CDS_SEC"2"
MATERIAL"FET"
VALUE"NTJD4001N"
PART_NUMBER"E40049-001"
LOCATION"Q9A2"
BOM_COST"SB"
SEC_TYPE"SMLF"
SEC"2"
ROOM"SB"
CDS_LIB"mstr_discrete"
CDS_LOCATION"Q9A2"
PACK_TYPE"SMLF";
"GATE <SIZE -1..0>"
$PN"5"32;
"SOURCE <SIZE-1..0>"
$PN"4"2;
"DRAIN <SIZE -1..0>"
$PN"3"33;
%"GND"
"1","(-3950,850)","0","mstr_symbols","I181";
;
HDL_POWER"GND"
BODY_TYPE"PLUMBING"
VOLTAGE"0.0V"
CDS_LIB"mstr_symbols"
SIZE"1B";
"A\NAC"2;
%"P3V3_STBY"
"1","(-4725,1550)","0","mstr_symbols","I182";
;
HDL_POWER"P3V3_STBY"
BODY_TYPE"PLUMBING"
SIZE"1B"
CDS_LIB"mstr_symbols"
VOLTAGE"3.3V";
"G\NAC"3;
%"RES"
"2","(-4725,1350)","0","mstr_discrete","I183";
;
CDS_SEC"1"
LOCATION"R9A18"
PART_NUMBER"G21796-072"
TOLERANCE"1%"
VALUE"4.75K"
MATERIAL"CHIP"
WATTAGE"1/16W"
PACK_TYPE"0402"
ROOM"SB"
SEC"1"
BOM_COST"SB"
SEC_TYPE"0402"
CDS_LOCATION"R9A18"
CDS_LIB"mstr_discrete";
"A"
$PN"1"3;
"B"
$PN"2"32;
%"GND"
"1","(-4725,425)","0","mstr_symbols","I184";
;
HDL_POWER"GND"
BODY_TYPE"PLUMBING"
CDS_LIB"mstr_symbols"
SIZE"1B"
VOLTAGE"0.0V";
"A\NAC"4;
%"P3V3_STBY"
"1","(-5175,1150)","0","mstr_symbols","I185";
;
HDL_POWER"P3V3_STBY"
BODY_TYPE"PLUMBING"
SIZE"1B"
CDS_LIB"mstr_symbols"
VOLTAGE"3.3V";
"G\NAC"5;
%"RES"
"2","(-5175,900)","0","mstr_discrete","I186";
;
CDS_SEC"1"
VALUE"4.75K"
LOCATION"R9A21"
WATTAGE"1/16W"
PART_NUMBER"G21796-072"
TOLERANCE"1%"
PACK_TYPE"0402"
MATERIAL"CHIP"
BOM_COST"SB"
ROOM"SB"
CDS_LOCATION"R9A21"
SEC"1"
SEC_TYPE"0402"
CDS_LIB"mstr_discrete";
"A"
$PN"1"5;
"B"
$PN"2"31;
%"RES"
"1","(-6750,3700)","0","mstr_discrete","I189";
;
CDS_SEC"1"
PACK_TYPE"0402"
LOCATION"R7C26"
WATTAGE"1/16W"
PART_NUMBER"G21796-074"
TOLERANCE"1%"
MATERIAL"CHIP"
VALUE"33.2"
ROOM"SYS_CLOCK"
SEC_TYPE"0402"
SEC"1"
BOM_COST"SM_CONTROLLER"
CDS_LIB"mstr_discrete"
CDS_LOCATION"R7C26";
"B"
$PN"2"104;
"A"
$PN"1"82;
%"RES"
"2","(-1700,4725)","0","mstr_discrete","I213";
;
CDS_SEC"1"
CDS_LOCATION"R2U48"
MATERIAL"CHIP"
PART_NUMBER"G21796-072"
PACK_TYPE"0402"
TOLERANCE"1%"
LOCATION"R2U48"
VALUE"4.75K"
WATTAGE"1/16W"
SEC"1"
SEC_TYPE"0402"
CDS_LIB"mstr_discrete";
"A"
$PN"1"6;
"B"
$PN"2"56;
%"P3V3_STBY"
"1","(-1700,4900)","0","mstr_symbols","I214";
;
HDL_POWER"P3V3_STBY"
BODY_TYPE"PLUMBING"
CDS_LIB"mstr_symbols"
SIZE"1B"
VOLTAGE"3.3V";
"G\NAC"6;
%"RES"
"1","(-1200,4150)","0","mstr_discrete","I223";
;
CDS_SEC"1"
TOLERANCE"5%"
PART_NUMBER"G21497-005"
LOCATION"R2W3"
VALUE"0.0"
PACK_TYPE"0402"
WATTAGE"1/16W"
SEC"1"
SEC_TYPE"0402"
ROOM"CPU0"
MATERIAL"CHIP"
BOM_COST"PROC_SIDEBAND"
CDS_LIB"mstr_discrete"
CDS_LOCATION"R2W3";
"B"
$PN"2"41;
"A"
$PN"1"57;
%"RES"
"1","(-6925,2550)","0","mstr_discrete","I224";
;
CDS_SEC"1"
LOCATION"R2W4"
VALUE"0.0"
PACK_TYPE"0402"
WATTAGE"1/16W"
TOLERANCE"5%"
PART_NUMBER"G21497-005"
POP"NOPOP"
CDS_LIB"mstr_discrete"
BOM_COST"PROC_SIDEBAND"
MATERIAL"CHIP"
ROOM"CPU0"
SEC_TYPE"0402"
SEC"1"
CDS_LOCATION"R2W4";
"B"
$PN"2"96;
"A"
$PN"1"99;
%"RES"
"1","(-6950,4400)","0","mstr_discrete","I226";
;
CDS_SEC"1"
PART_NUMBER"G21497-005"
PACK_TYPE"0402"
VALUE"0.0"
WATTAGE"1/16W"
TOLERANCE"5%"
LOCATION"R7W13"
CDS_LOCATION"R7W13"
CDS_LIB"mstr_discrete"
BOM_COST"PROC_SIDEBAND"
MATERIAL"CHIP"
ROOM"CPU0"
SEC_TYPE"0402"
SEC"1";
"B"
$PN"2"112;
"A"
$PN"1"101;
%"RES"
"1","(-6700,4300)","0","mstr_discrete","I227";
;
PART_NUMBER"G21497-005"
POP"NOPOP"
VALUE"0.0"
PACK_TYPE"0402"
TOLERANCE"5%"
LOCATION"R7W15"
WATTAGE"1/16W"
CDS_LOCATION"R7W15"
SEC"1"
SEC_TYPE"0402"
ROOM"CPU0"
MATERIAL"CHIP"
BOM_COST"PROC_SIDEBAND"
CDS_LIB"mstr_discrete"
CDS_SEC"1";
"B"
$PN"2"110;
"A"
$PN"1"102;
%"RES"
"1","(-1475,4100)","0","mstr_discrete","I228";
;
CDS_SEC"1"
PACK_TYPE"0402"
POP"NOPOP"
VALUE"0.0"
WATTAGE"1/16W"
TOLERANCE"5%"
LOCATION"R2U50"
PART_NUMBER"G21497-005"
CDS_LOCATION"R2U50"
SEC"1"
SEC_TYPE"0402"
ROOM"CPU0"
MATERIAL"CHIP"
BOM_COST"PROC_SIDEBAND"
CDS_LIB"mstr_discrete";
"B"
$PN"2"35;
"A"
$PN"1"56;
%"RES"
"1","(-1550,4250)","0","mstr_discrete","I229";
;
CDS_SEC"1"
WATTAGE"1/16W"
PACK_TYPE"0402"
TOLERANCE"5%"
VALUE"0.0"
LOCATION"R7W17"
PART_NUMBER"G21497-005"
CDS_LOCATION"R7W17"
CDS_LIB"mstr_discrete"
BOM_COST"PROC_SIDEBAND"
MATERIAL"CHIP"
ROOM"CPU0"
SEC_TYPE"0402"
SEC"1";
"B"
$PN"2"36;
"A"
$PN"1"63;
%"RES"
"2","(-1700,1600)","0","mstr_discrete","I230";
;
TOLERANCE"1%"
PACK_TYPE"0402"
POP"NOPOP"
PART_NUMBER"G21796-072"
MATERIAL"CHIP"
WATTAGE"1/16W"
VALUE"4.75K"
LOCATION"R7W22"
CDS_SEC"1"
CDS_LIB"mstr_discrete"
SEC_TYPE"0402"
SEC"1"
ROOM"CPU0"
CDS_LOCATION"R7W22";
"A"
$PN"1"7;
"B"
$PN"2"26;
%"P3V3_STBY"
"1","(-1700,1800)","0","mstr_symbols","I231";
;
VOLTAGE"3.3V"
CDS_LIB"mstr_symbols"
SIZE"1B"
BODY_TYPE"PLUMBING"
HDL_POWER"P3V3_STBY";
"G\NAC"7;
END.
